(kicad_pcb
	(version 20260206)
	(generator "pcbnew")
	(generator_version "10.0")
	(general
		(thickness 1.6)
		(legacy_teardrops no)
	)
	(paper "A4")
	(title_block
		(title "15969-1a.1015WZS0858.brd")
		(comment 1 "Tioga Pass / footprints 110-115 of 295")
	)
	(layers
		(0 "F.Cu" signal "TOP")
		(4 "In1.Cu" signal "L2GND")
		(6 "In2.Cu" signal "L3")
		(8 "In3.Cu" signal "L4")
		(10 "In4.Cu" signal "L5GND")
		(2 "B.Cu" signal "BOTTOM")
		(9 "F.Adhes" user "F.Adhesive")
		(11 "B.Adhes" user "B.Adhesive")
		(13 "F.Paste" user "Package Geometry/Pastemask Top")
		(15 "B.Paste" user "Package Geometry/Pastemask Bottom")
		(5 "F.SilkS" user "Ref Des/Silkscreen Top")
		(7 "B.SilkS" user "Ref Des/Silkscreen Bottom")
		(1 "F.Mask" user "Board Geometry/Soldermask Top")
		(3 "B.Mask" user "Board Geometry/Soldermask Bottom")
		(17 "Dwgs.User" user "User.Drawings")
		(19 "Cmts.User" user "User.Comments")
		(21 "Eco1.User" user "User.Eco1")
		(23 "Eco2.User" user "User.Eco2")
		(25 "Edge.Cuts" user "Board Geometry/Outline")
		(27 "Margin" user)
		(31 "F.CrtYd" user "Package Geometry/Place Bound Top")
		(29 "B.CrtYd" user "Package Geometry/Place Bound Bottom")
		(35 "F.Fab" user "Ref Des/Assembly Top")
		(33 "B.Fab" user "Ref Des/Assembly Bottom")
	)
	(footprint ""
		(layer "F.Cu")
		(at 80.772 -24.4602 -90)
		(property "Reference" "R114"
			(at 0 0 270)
			(layer "F.SilkS")
			(hide yes)
			(effects
				(font
					(size 1.27 1.27)
				)
			)
		)
		(property "Value" "4K7R2F-GP"
			(at 0.064008 -3.993896 270)
			(unlocked yes)
			(layer "F.Fab")
			(hide yes)
			(effects
				(font
					(size 1.016 1.016)
					(thickness 0.1524)
				)
			)
		)
		(property "Device Type" "R402H16"
			(at 0.064008 -5.517896 270)
			(unlocked yes)
			(layer "F.Fab")
			(hide yes)
			(effects
				(font
					(size 1.016 1.016)
					(thickness 0.1524)
				)
			)
		)
		(duplicate_pad_numbers_are_jumpers no)
		(fp_line
			(start -0.508 -0.9398)
			(end -0.508 0.9398)
			(stroke
				(width 0.1524)
				(type default)
			)
			(layer "F.SilkS")
		)
		(fp_line
			(start 0.508 -0.9398)
			(end -0.508 -0.9398)
			(stroke
				(width 0.1524)
				(type default)
			)
			(layer "F.SilkS")
		)
		(fp_rect
			(start -0.508 0.9398)
			(end 0.508 -0.9398)
			(stroke
				(width 0)
				(type default)
			)
			(fill no)
			(layer "F.CrtYd")
		)
		(fp_rect
			(start -0.508 0.9398)
			(end 0.508 -0.9398)
			(stroke
				(width 0)
				(type default)
			)
			(fill no)
			(layer "F.Fab")
		)
		(pad "1" smd custom
			(at 0 -0.4445 270)
			(size 0.1397 0.1397)
			(layers "F.Cu" "F.Mask" "F.Paste")
			(net "P3V3_STBY")
			(options
				(clearance outline)
				(anchor circle)
			)
			(primitives
				(gr_poly
					(pts
						(arc
							(start -0.1778 -0.2794)
							(mid -0.249642 -0.249642)
							(end -0.2794 -0.1778)
						)
						(arc
							(start -0.2794 0.1778)
							(mid -0.249642 0.249642)
							(end -0.1778 0.2794)
						)
						(arc
							(start 0.1778 0.2794)
							(mid 0.249642 0.249642)
							(end 0.2794 0.1778)
						)
						(arc
							(start 0.2794 -0.1778)
							(mid 0.249642 -0.249642)
							(end 0.1778 -0.2794)
						)
					)
					(width 0)
					(fill yes)
				)
			)
		)
		(pad "2" smd custom
			(at 0 0.4445 270)
			(size 0.1397 0.1397)
			(layers "F.Cu" "F.Mask" "F.Paste")
			(net "PCIE_SLOT3_PRSNT2_3_N")
			(options
				(clearance outline)
				(anchor circle)
			)
			(primitives
				(gr_poly
					(pts
						(arc
							(start -0.1778 -0.2794)
							(mid -0.249642 -0.249642)
							(end -0.2794 -0.1778)
						)
						(arc
							(start -0.2794 0.1778)
							(mid -0.249642 0.249642)
							(end -0.1778 0.2794)
						)
						(arc
							(start 0.1778 0.2794)
							(mid 0.249642 0.249642)
							(end 0.2794 0.1778)
						)
						(arc
							(start 0.2794 -0.1778)
							(mid 0.249642 -0.249642)
							(end 0.1778 -0.2794)
						)
					)
					(width 0)
					(fill yes)
				)
			)
		)
	)
	(footprint ""
		(layer "F.Cu")
		(at 119.9388 -16.637 90)
		(property "Reference" "R47"
			(at 0 0 90)
			(layer "F.SilkS")
			(hide yes)
			(effects
				(font
					(size 1.27 1.27)
				)
			)
		)
		(property "Value" "4K7R2F-GP"
			(at 0.064008 -3.993896 90)
			(unlocked yes)
			(layer "F.Fab")
			(hide yes)
			(effects
				(font
					(size 1.016 1.016)
					(thickness 0.1524)
				)
			)
		)
		(property "Device Type" "R402H16"
			(at 0.064008 -5.517896 90)
			(unlocked yes)
			(layer "F.Fab")
			(hide yes)
			(effects
				(font
					(size 1.016 1.016)
					(thickness 0.1524)
				)
			)
		)
		(duplicate_pad_numbers_are_jumpers no)
		(fp_line
			(start 0.508 -0.9398)
			(end -0.508 -0.9398)
			(stroke
				(width 0.1524)
				(type default)
			)
			(layer "F.SilkS")
		)
		(fp_line
			(start -0.508 -0.9398)
			(end -0.508 0.9398)
			(stroke
				(width 0.1524)
				(type default)
			)
			(layer "F.SilkS")
		)
		(fp_rect
			(start -0.508 0.9398)
			(end 0.508 -0.9398)
			(stroke
				(width 0)
				(type default)
			)
			(fill no)
			(layer "F.CrtYd")
		)
		(fp_rect
			(start -0.508 0.9398)
			(end 0.508 -0.9398)
			(stroke
				(width 0)
				(type default)
			)
			(fill no)
			(layer "F.Fab")
		)
		(pad "1" smd custom
			(at 0 -0.4445 90)
			(size 0.1397 0.1397)
			(layers "F.Cu" "F.Mask" "F.Paste")
			(net "P3V3_STBY")
			(options
				(clearance outline)
				(anchor circle)
			)
			(primitives
				(gr_poly
					(pts
						(arc
							(start -0.1778 -0.2794)
							(mid -0.249642 -0.249642)
							(end -0.2794 -0.1778)
						)
						(arc
							(start -0.2794 0.1778)
							(mid -0.249642 0.249642)
							(end -0.1778 0.2794)
						)
						(arc
							(start 0.1778 0.2794)
							(mid 0.249642 0.249642)
							(end 0.2794 0.1778)
						)
						(arc
							(start 0.2794 -0.1778)
							(mid 0.249642 -0.249642)
							(end 0.1778 -0.2794)
						)
					)
					(width 0)
					(fill yes)
				)
			)
		)
		(pad "2" smd custom
			(at 0 0.4445 90)
			(size 0.1397 0.1397)
			(layers "F.Cu" "F.Mask" "F.Paste")
			(net "PCIE_SLOT2_PRSNT2_3_N")
			(options
				(clearance outline)
				(anchor circle)
			)
			(primitives
				(gr_poly
					(pts
						(arc
							(start -0.1778 -0.2794)
							(mid -0.249642 -0.249642)
							(end -0.2794 -0.1778)
						)
						(arc
							(start -0.2794 0.1778)
							(mid -0.249642 0.249642)
							(end -0.1778 0.2794)
						)
						(arc
							(start 0.1778 0.2794)
							(mid 0.249642 0.249642)
							(end 0.2794 0.1778)
						)
						(arc
							(start 0.2794 -0.1778)
							(mid 0.249642 -0.249642)
							(end 0.1778 -0.2794)
						)
					)
					(width 0)
					(fill yes)
				)
			)
		)
	)
	(footprint ""
		(layer "F.Cu")
		(at 112.7252 0.4064 180)
		(property "Reference" "R10"
			(at 0 0 180)
			(layer "F.SilkS")
			(hide yes)
			(effects
				(font
					(size 1.27 1.27)
				)
			)
		)
		(property "Value" "4K7R2F-GP"
			(at 0.064008 -3.993896 180)
			(unlocked yes)
			(layer "F.Fab")
			(hide yes)
			(effects
				(font
					(size 1.016 1.016)
					(thickness 0.1524)
				)
			)
		)
		(property "Device Type" "R402H16"
			(at 0.064008 -5.517896 180)
			(unlocked yes)
			(layer "F.Fab")
			(hide yes)
			(effects
				(font
					(size 1.016 1.016)
					(thickness 0.1524)
				)
			)
		)
		(duplicate_pad_numbers_are_jumpers no)
		(fp_line
			(start 0.508 -0.9398)
			(end -0.508 -0.9398)
			(stroke
				(width 0.1524)
				(type default)
			)
			(layer "F.SilkS")
		)
		(fp_line
			(start -0.508 -0.9398)
			(end -0.508 0.9398)
			(stroke
				(width 0.1524)
				(type default)
			)
			(layer "F.SilkS")
		)
		(fp_rect
			(start -0.508 0.9398)
			(end 0.508 -0.9398)
			(stroke
				(width 0)
				(type default)
			)
			(fill no)
			(layer "F.CrtYd")
		)
		(fp_rect
			(start -0.508 0.9398)
			(end 0.508 -0.9398)
			(stroke
				(width 0)
				(type default)
			)
			(fill no)
			(layer "F.Fab")
		)
		(pad "1" smd custom
			(at 0 -0.4445 180)
			(size 0.1397 0.1397)
			(layers "F.Cu" "F.Mask" "F.Paste")
			(net "P3V3_STBY")
			(options
				(clearance outline)
				(anchor circle)
			)
			(primitives
				(gr_poly
					(pts
						(arc
							(start -0.1778 -0.2794)
							(mid -0.249642 -0.249642)
							(end -0.2794 -0.1778)
						)
						(arc
							(start -0.2794 0.1778)
							(mid -0.249642 0.249642)
							(end -0.1778 0.2794)
						)
						(arc
							(start 0.1778 0.2794)
							(mid 0.249642 0.249642)
							(end 0.2794 0.1778)
						)
						(arc
							(start 0.2794 -0.1778)
							(mid 0.249642 -0.249642)
							(end 0.1778 -0.2794)
						)
					)
					(width 0)
					(fill yes)
				)
			)
		)
		(pad "2" smd custom
			(at 0 0.4445 180)
			(size 0.1397 0.1397)
			(layers "F.Cu" "F.Mask" "F.Paste")
			(net "PU_B_MUX_SDA2")
			(options
				(clearance outline)
				(anchor circle)
			)
			(primitives
				(gr_poly
					(pts
						(arc
							(start -0.1778 -0.2794)
							(mid -0.249642 -0.249642)
							(end -0.2794 -0.1778)
						)
						(arc
							(start -0.2794 0.1778)
							(mid -0.249642 0.249642)
							(end -0.1778 0.2794)
						)
						(arc
							(start 0.1778 0.2794)
							(mid 0.249642 0.249642)
							(end 0.2794 0.1778)
						)
						(arc
							(start 0.2794 -0.1778)
							(mid 0.249642 -0.249642)
							(end 0.1778 -0.2794)
						)
					)
					(width 0)
					(fill yes)
				)
			)
		)
	)
	(footprint ""
		(layer "F.Cu")
		(at 118.7958 -32.3596 90)
		(property "Reference" "RU29"
			(at 0 0 90)
			(layer "F.SilkS")
			(hide yes)
			(effects
				(font
					(size 1.27 1.27)
				)
			)
		)
		(property "Value" "10KR2F-2-GP"
			(at 0.064008 -3.993896 90)
			(unlocked yes)
			(layer "F.Fab")
			(hide yes)
			(effects
				(font
					(size 1.016 1.016)
					(thickness 0.1524)
				)
			)
		)
		(property "Device Type" "R402H16"
			(at 0.064008 -5.517896 90)
			(unlocked yes)
			(layer "F.Fab")
			(hide yes)
			(effects
				(font
					(size 1.016 1.016)
					(thickness 0.1524)
				)
			)
		)
		(duplicate_pad_numbers_are_jumpers no)
		(fp_line
			(start 0.508 -0.9398)
			(end -0.508 -0.9398)
			(stroke
				(width 0.1524)
				(type default)
			)
			(layer "F.SilkS")
		)
		(fp_line
			(start -0.508 -0.9398)
			(end -0.508 0.9398)
			(stroke
				(width 0.1524)
				(type default)
			)
			(layer "F.SilkS")
		)
		(fp_rect
			(start -0.508 0.9398)
			(end 0.508 -0.9398)
			(stroke
				(width 0)
				(type default)
			)
			(fill no)
			(layer "F.CrtYd")
		)
		(fp_rect
			(start -0.508 0.9398)
			(end 0.508 -0.9398)
			(stroke
				(width 0)
				(type default)
			)
			(fill no)
			(layer "F.Fab")
		)
		(pad "1" smd custom
			(at 0 -0.4445 90)
			(size 0.1397 0.1397)
			(layers "F.Cu" "F.Mask" "F.Paste")
			(net "P3V3_USB_HUB")
			(options
				(clearance outline)
				(anchor circle)
			)
			(primitives
				(gr_poly
					(pts
						(arc
							(start -0.1778 -0.2794)
							(mid -0.249642 -0.249642)
							(end -0.2794 -0.1778)
						)
						(arc
							(start -0.2794 0.1778)
							(mid -0.249642 0.249642)
							(end -0.1778 0.2794)
						)
						(arc
							(start 0.1778 0.2794)
							(mid 0.249642 0.249642)
							(end 0.2794 0.1778)
						)
						(arc
							(start 0.2794 -0.1778)
							(mid 0.249642 -0.249642)
							(end 0.1778 -0.2794)
						)
					)
					(width 0)
					(fill yes)
				)
			)
		)
		(pad "2" smd custom
			(at 0 0.4445 90)
			(size 0.1397 0.1397)
			(layers "F.Cu" "F.Mask" "F.Paste")
			(net "USB_DP2")
			(options
				(clearance outline)
				(anchor circle)
			)
			(primitives
				(gr_poly
					(pts
						(arc
							(start -0.1778 -0.2794)
							(mid -0.249642 -0.249642)
							(end -0.2794 -0.1778)
						)
						(arc
							(start -0.2794 0.1778)
							(mid -0.249642 0.249642)
							(end -0.1778 0.2794)
						)
						(arc
							(start 0.1778 0.2794)
							(mid 0.249642 0.249642)
							(end 0.2794 0.1778)
						)
						(arc
							(start 0.2794 -0.1778)
							(mid 0.249642 -0.249642)
							(end 0.1778 -0.2794)
						)
					)
					(width 0)
					(fill yes)
				)
			)
		)
	)
	(footprint ""
		(layer "F.Cu")
		(at 140.5001 -25.584912 -90)
		(property "Reference" "H2"
			(at 0 0 270)
			(layer "F.SilkS")
			(hide yes)
			(effects
				(font
					(size 1.27 1.27)
				)
			)
		)
		(property "Value" "STFT363B238R224H453-GP"
			(at 7.0612 1.4605 270)
			(unlocked yes)
			(layer "F.Fab")
			(hide yes)
			(effects
				(font
					(size 1.016 1.016)
					(thickness 0.1524)
				)
			)
		)
		(property "Device Type" "STFT363B238R224H453"
			(at 7.0612 -0.0635 270)
			(unlocked yes)
			(layer "F.Fab")
			(hide yes)
			(effects
				(font
					(size 1.016 1.016)
					(thickness 0.1524)
				)
			)
		)
		(duplicate_pad_numbers_are_jumpers no)
		(fp_circle
			(center 0 0)
			(end 0 -5.3594)
			(stroke
				(width 0.3048)
				(type default)
			)
			(fill no)
			(layer "F.SilkS")
		)
		(fp_poly
			(pts
				(arc
					(start 0 -3.5306)
					(mid 0 3.5306)
					(end 0 -3.5306)
				)
			)
			(stroke
				(width 0)
				(type default)
			)
			(fill no)
			(layer "B.CrtYd")
		)
		(fp_poly
			(pts
				(arc
					(start 0 -5.0038)
					(mid 0 5.0038)
					(end 0 -5.0038)
				)
			)
			(stroke
				(width 0)
				(type default)
			)
			(fill no)
			(layer "F.CrtYd")
		)
		(fp_poly
			(pts
				(arc
					(start 5.5118 0.00635)
					(mid -5.511804 0)
					(end 5.5118 -0.00635)
				)
				(arc
					(start 5.0038 -0.00635)
					(mid -5.003804 0)
					(end 5.0038 0.00635)
				)
			)
			(stroke
				(width 0)
				(type default)
			)
			(fill no)
			(layer "F.CrtYd")
		)
		(fp_poly
			(pts
				(arc
					(start 0 -3.5306)
					(mid 0 3.5306)
					(end 0 -3.5306)
				)
			)
			(stroke
				(width 0)
				(type default)
			)
			(fill no)
			(layer "B.Fab")
		)
		(fp_poly
			(pts
				(arc
					(start 0 -5.5118)
					(mid 0 5.5118)
					(end 0 -5.5118)
				)
			)
			(stroke
				(width 0)
				(type default)
			)
			(fill no)
			(layer "F.Fab")
		)
		(pad "1" thru_hole circle
			(at 0 0 270)
			(size 9.2202 9.2202)
			(drill 5.6896)
			(layers "*.Cu" "*.Mask")
			(remove_unused_layers no)
			(net "GND")
			(clearance -1.2573)
			(thermal_gap 0.3302)
			(padstack
				(mode front_inner_back)
				(layer "Inner"
					(shape circle)
					(size 6.0452 6.0452)
					(clearance 0.3302)
				)
				(layer "B.Cu"
					(shape circle)
					(size 6.0452 6.0452)
					(clearance 0.3302)
				)
			)
		)
	)
	(footprint ""
		(layer "F.Cu")
		(at 132.207 -4.6736 90)
		(property "Reference" "R143"
			(at 0 0 90)
			(layer "F.SilkS")
			(hide yes)
			(effects
				(font
					(size 1.27 1.27)
				)
			)
		)
		(property "Value" "10KR2F-2-GP"
			(at 0.064008 -3.993896 90)
			(unlocked yes)
			(layer "F.Fab")
			(hide yes)
			(effects
				(font
					(size 1.016 1.016)
					(thickness 0.1524)
				)
			)
		)
		(property "Device Type" "R402H16"
			(at 0.064008 -5.517896 90)
			(unlocked yes)
			(layer "F.Fab")
			(hide yes)
			(effects
				(font
					(size 1.016 1.016)
					(thickness 0.1524)
				)
			)
		)
		(duplicate_pad_numbers_are_jumpers no)
		(fp_line
			(start 0.508 -0.9398)
			(end -0.508 -0.9398)
			(stroke
				(width 0.1524)
				(type default)
			)
			(layer "F.SilkS")
		)
		(fp_line
			(start -0.508 -0.9398)
			(end -0.508 0.9398)
			(stroke
				(width 0.1524)
				(type default)
			)
			(layer "F.SilkS")
		)
		(fp_rect
			(start -0.508 0.9398)
			(end 0.508 -0.9398)
			(stroke
				(width 0)
				(type default)
			)
			(fill no)
			(layer "F.CrtYd")
		)
		(fp_rect
			(start -0.508 0.9398)
			(end 0.508 -0.9398)
			(stroke
				(width 0)
				(type default)
			)
			(fill no)
			(layer "F.Fab")
		)
		(pad "1" smd custom
			(at 0 -0.4445 90)
			(size 0.1397 0.1397)
			(layers "F.Cu" "F.Mask" "F.Paste")
			(net "GPIO_P_EXP_A2")
			(options
				(clearance outline)
				(anchor circle)
			)
			(primitives
				(gr_poly
					(pts
						(arc
							(start -0.1778 -0.2794)
							(mid -0.249642 -0.249642)
							(end -0.2794 -0.1778)
						)
						(arc
							(start -0.2794 0.1778)
							(mid -0.249642 0.249642)
							(end -0.1778 0.2794)
						)
						(arc
							(start 0.1778 0.2794)
							(mid 0.249642 0.249642)
							(end 0.2794 0.1778)
						)
						(arc
							(start 0.2794 -0.1778)
							(mid 0.249642 -0.249642)
							(end 0.1778 -0.2794)
						)
					)
					(width 0)
					(fill yes)
				)
			)
		)
		(pad "2" smd custom
			(at 0 0.4445 90)
			(size 0.1397 0.1397)
			(layers "F.Cu" "F.Mask" "F.Paste")
			(net "GND")
			(options
				(clearance outline)
				(anchor circle)
			)
			(primitives
				(gr_poly
					(pts
						(arc
							(start -0.1778 -0.2794)
							(mid -0.249642 -0.249642)
							(end -0.2794 -0.1778)
						)
						(arc
							(start -0.2794 0.1778)
							(mid -0.249642 0.249642)
							(end -0.1778 0.2794)
						)
						(arc
							(start 0.1778 0.2794)
							(mid 0.249642 0.249642)
							(end 0.2794 0.1778)
						)
						(arc
							(start 0.2794 -0.1778)
							(mid 0.249642 -0.249642)
							(end 0.1778 -0.2794)
						)
					)
					(width 0)
					(fill yes)
				)
			)
		)
	)
)
